(kicad_pcb
	(version 20260206)
	(generator "pcbnew")
	(generator_version "10.0")
	(general
		(thickness 1.6)
		(legacy_teardrops no)
	)
	(paper "A4")
	(title_block
		(title "peb — Lightning_PEB_BRD.brd")
		(comment 1 "Lightning (Wiwynn / Facebook NVMe JBOF) / footprints 1919-1926 of 2563")
	)
	(layers
		(0 "F.Cu" signal "TOP")
		(4 "In1.Cu" signal "L2GND")
		(6 "In2.Cu" signal "L3")
		(8 "In3.Cu" signal "L4VCC")
		(10 "In4.Cu" signal "L5VCC")
		(12 "In5.Cu" signal "L6")
		(14 "In6.Cu" signal "L7GND")
		(2 "B.Cu" signal "BOTTOM")
		(9 "F.Adhes" user "F.Adhesive")
		(11 "B.Adhes" user "B.Adhesive")
		(13 "F.Paste" user "Package Geometry/Pastemask Top")
		(15 "B.Paste" user "Package Geometry/Pastemask Bottom")
		(5 "F.SilkS" user "Ref Des/Silkscreen Top")
		(7 "B.SilkS" user "Ref Des/Silkscreen Bottom")
		(1 "F.Mask" user "Board Geometry/Soldermask Top")
		(3 "B.Mask" user "Board Geometry/Soldermask Bottom")
		(17 "Dwgs.User" user "User.Drawings")
		(19 "Cmts.User" user "User.Comments")
		(21 "Eco1.User" user "User.Eco1")
		(23 "Eco2.User" user "User.Eco2")
		(25 "Edge.Cuts" user "Board Geometry/Outline")
		(27 "Margin" user)
		(31 "F.CrtYd" user "Package Geometry/Place Bound Top")
		(29 "B.CrtYd" user "Package Geometry/Place Bound Bottom")
		(35 "F.Fab" user "Ref Des/Assembly Top")
		(33 "B.Fab" user "Ref Des/Assembly Bottom")
	)
	(footprint ""
		(layer "B.Cu")
		(at 40.005 -118.872)
		(property "Reference" "TP153"
			(at 0 0 0)
			(layer "B.SilkS")
			(hide yes)
			(effects
				(font
					(size 1.27 1.27)
				)
				(justify mirror)
			)
		)
		(property "Value" "TPAD28-2-GP"
			(at 0.0127 -1.6637 0)
			(unlocked yes)
			(layer "B.Fab")
			(hide yes)
			(effects
				(font
					(size 1.016 1.016)
					(thickness 0.1524)
				)
				(justify mirror)
			)
		)
		(property "Device Type" "TPAD28"
			(at 0.0127 -3.1877 0)
			(unlocked yes)
			(layer "B.Fab")
			(hide yes)
			(effects
				(font
					(size 1.016 1.016)
					(thickness 0.1524)
				)
				(justify mirror)
			)
		)
		(duplicate_pad_numbers_are_jumpers no)
		(fp_poly
			(pts
				(arc
					(start 0.3556 0)
					(mid -0.3556 0)
					(end 0.3556 0)
				)
			)
			(stroke
				(width 0)
				(type default)
			)
			(fill no)
			(layer "B.CrtYd")
		)
		(fp_poly
			(pts
				(arc
					(start 0.6096 0)
					(mid -0.6096 0)
					(end 0.6096 0)
				)
			)
			(stroke
				(width 0)
				(type default)
			)
			(fill no)
			(layer "B.Fab")
		)
		(pad "1" smd circle
			(at 0 0 180)
			(size 0.7112 0.7112)
			(layers "B.Cu" "B.Mask" "B.Paste")
			(net "TP_GPIOU3")
		)
	)
	(footprint ""
		(layer "B.Cu")
		(at 235.1024 -51.9938 -90)
		(property "Reference" "C33"
			(at 0 0 90)
			(layer "B.SilkS")
			(hide yes)
			(effects
				(font
					(size 1.27 1.27)
				)
				(justify mirror)
			)
		)
		(property "Value" "SCD1U16V1KX-1-GP"
			(at 2.8321 -1.7399 270)
			(unlocked yes)
			(layer "B.Fab")
			(hide yes)
			(effects
				(font
					(size 1.016 1.016)
					(thickness 0.1524)
				)
				(justify mirror)
			)
		)
		(property "Device Type" "C0201H13"
			(at 2.8321 -3.2639 270)
			(unlocked yes)
			(layer "B.Fab")
			(hide yes)
			(effects
				(font
					(size 1.016 1.016)
					(thickness 0.1524)
				)
				(justify mirror)
			)
		)
		(duplicate_pad_numbers_are_jumpers no)
		(fp_rect
			(start 0.2794 0.6477)
			(end -0.2794 -0.6477)
			(stroke
				(width 0)
				(type default)
			)
			(fill no)
			(layer "B.CrtYd")
		)
		(fp_rect
			(start 0.2794 0.6477)
			(end -0.2794 -0.6477)
			(stroke
				(width 0)
				(type default)
			)
			(fill no)
			(layer "B.Fab")
		)
		(pad "1" smd custom
			(at 0 -0.2794 90)
			(size 0.0762 0.0762)
			(layers "B.Cu" "B.Mask" "B.Paste")
			(net "DUT_VDD")
			(options
				(clearance outline)
				(anchor circle)
			)
			(primitives
				(gr_poly
					(pts
						(arc
							(start 0.1524 0.127)
							(mid 0.137521 0.162921)
							(end 0.1016 0.1778)
						)
						(arc
							(start -0.1016 0.1778)
							(mid -0.137521 0.162921)
							(end -0.1524 0.127)
						)
						(arc
							(start -0.1524 -0.127)
							(mid -0.137521 -0.162921)
							(end -0.1016 -0.1778)
						)
						(arc
							(start 0.1016 -0.1778)
							(mid 0.137521 -0.162921)
							(end 0.1524 -0.127)
						)
					)
					(width 0)
					(fill yes)
				)
			)
		)
		(pad "2" smd custom
			(at 0 0.2794 90)
			(size 0.0762 0.0762)
			(layers "B.Cu" "B.Mask" "B.Paste")
			(net "GND")
			(options
				(clearance outline)
				(anchor circle)
			)
			(primitives
				(gr_poly
					(pts
						(arc
							(start 0.1524 0.127)
							(mid 0.137521 0.162921)
							(end 0.1016 0.1778)
						)
						(arc
							(start -0.1016 0.1778)
							(mid -0.137521 0.162921)
							(end -0.1524 0.127)
						)
						(arc
							(start -0.1524 -0.127)
							(mid -0.137521 -0.162921)
							(end -0.1016 -0.1778)
						)
						(arc
							(start 0.1016 -0.1778)
							(mid 0.137521 -0.162921)
							(end 0.1524 -0.127)
						)
					)
					(width 0)
					(fill yes)
				)
			)
		)
	)
	(footprint ""
		(layer "B.Cu")
		(at 232.61066 -41.00068 -90)
		(property "Reference" "TP204"
			(at 0 0 90)
			(layer "B.SilkS")
			(hide yes)
			(effects
				(font
					(size 1.27 1.27)
				)
				(justify mirror)
			)
		)
		(property "Value" "TPAD28-2-GP"
			(at 0.0127 -1.6637 270)
			(unlocked yes)
			(layer "B.Fab")
			(hide yes)
			(effects
				(font
					(size 1.016 1.016)
					(thickness 0.1524)
				)
				(justify mirror)
			)
		)
		(property "Device Type" "TPAD28"
			(at 0.0127 -3.1877 270)
			(unlocked yes)
			(layer "B.Fab")
			(hide yes)
			(effects
				(font
					(size 1.016 1.016)
					(thickness 0.1524)
				)
				(justify mirror)
			)
		)
		(duplicate_pad_numbers_are_jumpers no)
		(fp_poly
			(pts
				(arc
					(start 0 -0.3556)
					(mid 0 0.3556)
					(end 0 -0.3556)
				)
			)
			(stroke
				(width 0)
				(type default)
			)
			(fill no)
			(layer "B.CrtYd")
		)
		(fp_poly
			(pts
				(arc
					(start 0 -0.6096)
					(mid 0 0.6096)
					(end 0 -0.6096)
				)
			)
			(stroke
				(width 0)
				(type default)
			)
			(fill no)
			(layer "B.Fab")
		)
		(pad "1" smd circle
			(at 0 0 90)
			(size 0.7112 0.7112)
			(layers "B.Cu" "B.Mask" "B.Paste")
			(net "RMII_CRS_DV")
		)
	)
	(footprint ""
		(layer "B.Cu")
		(at 222.25 -23.241 180)
		(property "Reference" "R832"
			(at 0 0 0)
			(layer "B.SilkS")
			(hide yes)
			(effects
				(font
					(size 1.27 1.27)
				)
				(justify mirror)
			)
		)
		(property "Value" "0R2J-2-GP"
			(at -0.064008 -3.993896 180)
			(unlocked yes)
			(layer "B.Fab")
			(hide yes)
			(effects
				(font
					(size 1.016 1.016)
					(thickness 0.1524)
				)
				(justify mirror)
			)
		)
		(property "Device Type" "R402H16"
			(at -0.064008 -5.517896 180)
			(unlocked yes)
			(layer "B.Fab")
			(hide yes)
			(effects
				(font
					(size 1.016 1.016)
					(thickness 0.1524)
				)
				(justify mirror)
			)
		)
		(duplicate_pad_numbers_are_jumpers no)
		(fp_line
			(start 0.508 -0.9398)
			(end 0.508 0.9398)
			(stroke
				(width 0.1524)
				(type default)
			)
			(layer "B.SilkS")
		)
		(fp_line
			(start -0.508 -0.9398)
			(end 0.508 -0.9398)
			(stroke
				(width 0.1524)
				(type default)
			)
			(layer "B.SilkS")
		)
		(fp_rect
			(start 0.508 0.9398)
			(end -0.508 -0.9398)
			(stroke
				(width 0)
				(type default)
			)
			(fill no)
			(layer "B.CrtYd")
		)
		(fp_rect
			(start 0.508 0.9398)
			(end -0.508 -0.9398)
			(stroke
				(width 0)
				(type default)
			)
			(fill no)
			(layer "B.Fab")
		)
		(pad "1" smd custom
			(at 0 -0.4445)
			(size 0.1397 0.1397)
			(layers "B.Cu" "B.Mask" "B.Paste")
			(net "HOST8_RST_N_LS")
			(options
				(clearance outline)
				(anchor circle)
			)
			(primitives
				(gr_poly
					(pts
						(arc
							(start -0.1778 0.2794)
							(mid -0.249642 0.249642)
							(end -0.2794 0.1778)
						)
						(arc
							(start -0.2794 -0.1778)
							(mid -0.249642 -0.249642)
							(end -0.1778 -0.2794)
						)
						(arc
							(start 0.1778 -0.2794)
							(mid 0.249642 -0.249642)
							(end 0.2794 -0.1778)
						)
						(arc
							(start 0.2794 0.1778)
							(mid 0.249642 0.249642)
							(end 0.1778 0.2794)
						)
					)
					(width 0)
					(fill yes)
				)
			)
		)
		(pad "2" smd custom
			(at 0 0.4445)
			(size 0.1397 0.1397)
			(layers "B.Cu" "B.Mask" "B.Paste")
			(net "LBI_ADDR_7_R")
			(options
				(clearance outline)
				(anchor circle)
			)
			(primitives
				(gr_poly
					(pts
						(arc
							(start -0.1778 0.2794)
							(mid -0.249642 0.249642)
							(end -0.2794 0.1778)
						)
						(arc
							(start -0.2794 -0.1778)
							(mid -0.249642 -0.249642)
							(end -0.1778 -0.2794)
						)
						(arc
							(start 0.1778 -0.2794)
							(mid 0.249642 -0.249642)
							(end 0.2794 -0.1778)
						)
						(arc
							(start 0.2794 0.1778)
							(mid 0.249642 0.249642)
							(end 0.1778 0.2794)
						)
					)
					(width 0)
					(fill yes)
				)
			)
		)
	)
	(footprint ""
		(layer "B.Cu")
		(at 20.955 -135.763 90)
		(property "Reference" "R638"
			(at 0 0 90)
			(layer "B.SilkS")
			(hide yes)
			(effects
				(font
					(size 1.27 1.27)
				)
				(justify mirror)
			)
		)
		(property "Value" "22R2F-1-GP"
			(at -0.064008 -3.993896 90)
			(unlocked yes)
			(layer "B.Fab")
			(hide yes)
			(effects
				(font
					(size 1.016 1.016)
					(thickness 0.1524)
				)
				(justify mirror)
			)
		)
		(property "Device Type" "R402H16"
			(at -0.064008 -5.517896 90)
			(unlocked yes)
			(layer "B.Fab")
			(hide yes)
			(effects
				(font
					(size 1.016 1.016)
					(thickness 0.1524)
				)
				(justify mirror)
			)
		)
		(duplicate_pad_numbers_are_jumpers no)
		(fp_line
			(start 0.508 -0.9398)
			(end 0.508 0.9398)
			(stroke
				(width 0.1524)
				(type default)
			)
			(layer "B.SilkS")
		)
		(fp_line
			(start -0.508 -0.9398)
			(end 0.508 -0.9398)
			(stroke
				(width 0.1524)
				(type default)
			)
			(layer "B.SilkS")
		)
		(fp_rect
			(start 0.508 0.9398)
			(end -0.508 -0.9398)
			(stroke
				(width 0)
				(type default)
			)
			(fill no)
			(layer "B.CrtYd")
		)
		(fp_rect
			(start 0.508 0.9398)
			(end -0.508 -0.9398)
			(stroke
				(width 0)
				(type default)
			)
			(fill no)
			(layer "B.Fab")
		)
		(pad "1" smd custom
			(at 0 -0.4445 270)
			(size 0.1397 0.1397)
			(layers "B.Cu" "B.Mask" "B.Paste")
			(net "ROMD0_R")
			(options
				(clearance outline)
				(anchor circle)
			)
			(primitives
				(gr_poly
					(pts
						(arc
							(start -0.1778 0.2794)
							(mid -0.249642 0.249642)
							(end -0.2794 0.1778)
						)
						(arc
							(start -0.2794 -0.1778)
							(mid -0.249642 -0.249642)
							(end -0.1778 -0.2794)
						)
						(arc
							(start 0.1778 -0.2794)
							(mid 0.249642 -0.249642)
							(end 0.2794 -0.1778)
						)
						(arc
							(start 0.2794 0.1778)
							(mid 0.249642 0.249642)
							(end 0.1778 0.2794)
						)
					)
					(width 0)
					(fill yes)
				)
			)
		)
		(pad "2" smd custom
			(at 0 0.4445 270)
			(size 0.1397 0.1397)
			(layers "B.Cu" "B.Mask" "B.Paste")
			(net "ROMD0")
			(options
				(clearance outline)
				(anchor circle)
			)
			(primitives
				(gr_poly
					(pts
						(arc
							(start -0.1778 0.2794)
							(mid -0.249642 0.249642)
							(end -0.2794 0.1778)
						)
						(arc
							(start -0.2794 -0.1778)
							(mid -0.249642 -0.249642)
							(end -0.1778 -0.2794)
						)
						(arc
							(start 0.1778 -0.2794)
							(mid 0.249642 -0.249642)
							(end 0.2794 -0.1778)
						)
						(arc
							(start 0.2794 0.1778)
							(mid 0.249642 0.249642)
							(end 0.1778 0.2794)
						)
					)
					(width 0)
					(fill yes)
				)
			)
		)
	)
	(footprint ""
		(layer "B.Cu")
		(at 41.656 -201.549 180)
		(property "Reference" "R882"
			(at 0 0 0)
			(layer "B.SilkS")
			(hide yes)
			(effects
				(font
					(size 1.27 1.27)
				)
				(justify mirror)
			)
		)
		(property "Value" "0R2J-2-GP"
			(at -0.064008 -3.993896 180)
			(unlocked yes)
			(layer "B.Fab")
			(hide yes)
			(effects
				(font
					(size 1.016 1.016)
					(thickness 0.1524)
				)
				(justify mirror)
			)
		)
		(property "Device Type" "R402H16"
			(at -0.064008 -5.517896 180)
			(unlocked yes)
			(layer "B.Fab")
			(hide yes)
			(effects
				(font
					(size 1.016 1.016)
					(thickness 0.1524)
				)
				(justify mirror)
			)
		)
		(duplicate_pad_numbers_are_jumpers no)
		(fp_line
			(start 0.508 -0.9398)
			(end 0.508 0.9398)
			(stroke
				(width 0.1524)
				(type default)
			)
			(layer "B.SilkS")
		)
		(fp_line
			(start -0.508 -0.9398)
			(end 0.508 -0.9398)
			(stroke
				(width 0.1524)
				(type default)
			)
			(layer "B.SilkS")
		)
		(fp_rect
			(start 0.508 0.9398)
			(end -0.508 -0.9398)
			(stroke
				(width 0)
				(type default)
			)
			(fill no)
			(layer "B.CrtYd")
		)
		(fp_rect
			(start 0.508 0.9398)
			(end -0.508 -0.9398)
			(stroke
				(width 0)
				(type default)
			)
			(fill no)
			(layer "B.Fab")
		)
		(pad "1" smd custom
			(at 0 -0.4445)
			(size 0.1397 0.1397)
			(layers "B.Cu" "B.Mask" "B.Paste")
			(net "BMC_I2C6_C_FCB_SCL")
			(options
				(clearance outline)
				(anchor circle)
			)
			(primitives
				(gr_poly
					(pts
						(arc
							(start -0.1778 0.2794)
							(mid -0.249642 0.249642)
							(end -0.2794 0.1778)
						)
						(arc
							(start -0.2794 -0.1778)
							(mid -0.249642 -0.249642)
							(end -0.1778 -0.2794)
						)
						(arc
							(start 0.1778 -0.2794)
							(mid 0.249642 -0.249642)
							(end 0.2794 -0.1778)
						)
						(arc
							(start 0.2794 0.1778)
							(mid 0.249642 0.249642)
							(end 0.1778 0.2794)
						)
					)
					(width 0)
					(fill yes)
				)
			)
		)
		(pad "2" smd custom
			(at 0 0.4445)
			(size 0.1397 0.1397)
			(layers "B.Cu" "B.Mask" "B.Paste")
			(net "BUF_I2C6_C_FCB_SCL")
			(options
				(clearance outline)
				(anchor circle)
			)
			(primitives
				(gr_poly
					(pts
						(arc
							(start -0.1778 0.2794)
							(mid -0.249642 0.249642)
							(end -0.2794 0.1778)
						)
						(arc
							(start -0.2794 -0.1778)
							(mid -0.249642 -0.249642)
							(end -0.1778 -0.2794)
						)
						(arc
							(start 0.1778 -0.2794)
							(mid 0.249642 -0.249642)
							(end 0.2794 -0.1778)
						)
						(arc
							(start 0.2794 0.1778)
							(mid 0.249642 0.249642)
							(end 0.1778 0.2794)
						)
					)
					(width 0)
					(fill yes)
				)
			)
		)
	)
	(footprint ""
		(layer "B.Cu")
		(at 213.932008 -4.064)
		(property "Reference" "R3715"
			(at 0 0 0)
			(layer "B.SilkS")
			(hide yes)
			(effects
				(font
					(size 1.27 1.27)
				)
				(justify mirror)
			)
		)
		(property "Value" "1KR2F-3-GP"
			(at -0.064008 -3.993896 0)
			(unlocked yes)
			(layer "B.Fab")
			(hide yes)
			(effects
				(font
					(size 1.016 1.016)
					(thickness 0.1524)
				)
				(justify mirror)
			)
		)
		(property "Device Type" "R402H16"
			(at -0.064008 -5.517896 0)
			(unlocked yes)
			(layer "B.Fab")
			(hide yes)
			(effects
				(font
					(size 1.016 1.016)
					(thickness 0.1524)
				)
				(justify mirror)
			)
		)
		(duplicate_pad_numbers_are_jumpers no)
		(fp_line
			(start -0.508 -0.9398)
			(end 0.508 -0.9398)
			(stroke
				(width 0.1524)
				(type default)
			)
			(layer "B.SilkS")
		)
		(fp_line
			(start 0.508 -0.9398)
			(end 0.508 0.9398)
			(stroke
				(width 0.1524)
				(type default)
			)
			(layer "B.SilkS")
		)
		(fp_rect
			(start 0.508 0.9398)
			(end -0.508 -0.9398)
			(stroke
				(width 0)
				(type default)
			)
			(fill no)
			(layer "B.CrtYd")
		)
		(fp_rect
			(start 0.508 0.9398)
			(end -0.508 -0.9398)
			(stroke
				(width 0)
				(type default)
			)
			(fill no)
			(layer "B.Fab")
		)
		(pad "1" smd custom
			(at 0 -0.4445 180)
			(size 0.1397 0.1397)
			(layers "B.Cu" "B.Mask" "B.Paste")
			(net "HOST3_RST_N")
			(options
				(clearance outline)
				(anchor circle)
			)
			(primitives
				(gr_poly
					(pts
						(arc
							(start -0.1778 0.2794)
							(mid -0.249642 0.249642)
							(end -0.2794 0.1778)
						)
						(arc
							(start -0.2794 -0.1778)
							(mid -0.249642 -0.249642)
							(end -0.1778 -0.2794)
						)
						(arc
							(start 0.1778 -0.2794)
							(mid 0.249642 -0.249642)
							(end 0.2794 -0.1778)
						)
						(arc
							(start 0.2794 0.1778)
							(mid 0.249642 0.249642)
							(end 0.1778 0.2794)
						)
					)
					(width 0)
					(fill yes)
				)
			)
		)
		(pad "2" smd custom
			(at 0 0.4445 180)
			(size 0.1397 0.1397)
			(layers "B.Cu" "B.Mask" "B.Paste")
			(net "P3V3_STBY")
			(options
				(clearance outline)
				(anchor circle)
			)
			(primitives
				(gr_poly
					(pts
						(arc
							(start -0.1778 0.2794)
							(mid -0.249642 0.249642)
							(end -0.2794 0.1778)
						)
						(arc
							(start -0.2794 -0.1778)
							(mid -0.249642 -0.249642)
							(end -0.1778 -0.2794)
						)
						(arc
							(start 0.1778 -0.2794)
							(mid 0.249642 -0.249642)
							(end 0.2794 -0.1778)
						)
						(arc
							(start 0.2794 0.1778)
							(mid 0.249642 0.249642)
							(end 0.1778 0.2794)
						)
					)
					(width 0)
					(fill yes)
				)
			)
		)
	)
	(footprint ""
		(layer "B.Cu")
		(at 70.6247 -186.694318)
		(property "Reference" "R3236"
			(at 0 0 0)
			(layer "B.SilkS")
			(hide yes)
			(effects
				(font
					(size 1.27 1.27)
				)
				(justify mirror)
			)
		)
		(property "Value" "0R2J-2-GP"
			(at -0.064008 -3.993896 0)
			(unlocked yes)
			(layer "B.Fab")
			(hide yes)
			(effects
				(font
					(size 1.016 1.016)
					(thickness 0.1524)
				)
				(justify mirror)
			)
		)
		(property "Device Type" "R402H16"
			(at -0.064008 -5.517896 0)
			(unlocked yes)
			(layer "B.Fab")
			(hide yes)
			(effects
				(font
					(size 1.016 1.016)
					(thickness 0.1524)
				)
				(justify mirror)
			)
		)
		(duplicate_pad_numbers_are_jumpers no)
		(fp_line
			(start -0.508 -0.9398)
			(end 0.508 -0.9398)
			(stroke
				(width 0.1524)
				(type default)
			)
			(layer "B.SilkS")
		)
		(fp_line
			(start 0.508 -0.9398)
			(end 0.508 0.9398)
			(stroke
				(width 0.1524)
				(type default)
			)
			(layer "B.SilkS")
		)
		(fp_rect
			(start 0.508 0.9398)
			(end -0.508 -0.9398)
			(stroke
				(width 0)
				(type default)
			)
			(fill no)
			(layer "B.CrtYd")
		)
		(fp_rect
			(start 0.508 0.9398)
			(end -0.508 -0.9398)
			(stroke
				(width 0)
				(type default)
			)
			(fill no)
			(layer "B.Fab")
		)
		(pad "1" smd custom
			(at 0 -0.4445 180)
			(size 0.1397 0.1397)
			(layers "B.Cu" "B.Mask" "B.Paste")
			(net "SSD_PERST_Y11")
			(options
				(clearance outline)
				(anchor circle)
			)
			(primitives
				(gr_poly
					(pts
						(arc
							(start -0.1778 0.2794)
							(mid -0.249642 0.249642)
							(end -0.2794 0.1778)
						)
						(arc
							(start -0.2794 -0.1778)
							(mid -0.249642 -0.249642)
							(end -0.1778 -0.2794)
						)
						(arc
							(start 0.1778 -0.2794)
							(mid 0.249642 -0.249642)
							(end 0.2794 -0.1778)
						)
						(arc
							(start 0.2794 0.1778)
							(mid 0.249642 0.249642)
							(end 0.1778 0.2794)
						)
					)
					(width 0)
					(fill yes)
				)
			)
		)
		(pad "2" smd custom
			(at 0 0.4445 180)
			(size 0.1397 0.1397)
			(layers "B.Cu" "B.Mask" "B.Paste")
			(net "SSD_PERST#11_R")
			(options
				(clearance outline)
				(anchor circle)
			)
			(primitives
				(gr_poly
					(pts
						(arc
							(start -0.1778 0.2794)
							(mid -0.249642 0.249642)
							(end -0.2794 0.1778)
						)
						(arc
							(start -0.2794 -0.1778)
							(mid -0.249642 -0.249642)
							(end -0.1778 -0.2794)
						)
						(arc
							(start 0.1778 -0.2794)
							(mid 0.249642 -0.249642)
							(end 0.2794 -0.1778)
						)
						(arc
							(start 0.2794 0.1778)
							(mid 0.249642 0.249642)
							(end 0.1778 0.2794)
						)
					)
					(width 0)
					(fill yes)
				)
			)
		)
	)
)
